# S9S_MB_2U (Grand Teton) — schematic netlist excerpt (pin names and nets, part order shuffled) for the footprints in the layout excerpt that follows; sources: Cadence DE-HDL packaged netlist, KiCad conversion of 03242023_DA0F0TMBIJ0_F0T_Motherboard_J_brd_V01_OCP.brd

C107  Q_CAP  1UF 25V 10% X6S  pkg C0402  page 210 : A = P3V3_AUX_CLK_GEN_VDD_CK440 ; B = GND
PR1649  Q_RES  2K 1% CHIP  pkg 0402LF  page 262 : A = FM_P1V05_PCH_AUX_R_EN ; B = GND

(kicad_pcb
	(version 20260206)
	(generator "pcbnew")
	(generator_version "10.0")
	(general
		(thickness 1.6)
		(legacy_teardrops no)
	)
	(paper "A4")
	(title_block
		(title "03242023_DA0F0TMBIJ0_F0T_Motherboard_J_brd_V01_OCP.brd")
		(comment 1 "Grand Teton / footprints 5095-5096 of 6105")
	)
	(layers
		(0 "F.Cu" signal "TOP")
		(4 "In1.Cu" signal "GND")
		(6 "In2.Cu" signal "IN1")
		(8 "In3.Cu" signal "GND1")
		(10 "In4.Cu" signal "IN2")
		(12 "In5.Cu" signal "GND2")
		(14 "In6.Cu" signal "IN3")
		(16 "In7.Cu" signal "GND3")
		(18 "In8.Cu" signal "VCC")
		(20 "In9.Cu" signal "VCC1")
		(22 "In10.Cu" signal "GND4")
		(24 "In11.Cu" signal "IN4")
		(26 "In12.Cu" signal "GND5")
		(28 "In13.Cu" signal "IN5")
		(30 "In14.Cu" signal "GND6")
		(32 "In15.Cu" signal "IN6")
		(34 "In16.Cu" signal "GND7")
		(2 "B.Cu" signal "BOTTOM")
		(9 "F.Adhes" user "F.Adhesive")
		(11 "B.Adhes" user "B.Adhesive")
		(13 "F.Paste" user "Package Geometry/Pastemask Top")
		(15 "B.Paste" user "Package Geometry/Pastemask Bottom")
		(5 "F.SilkS" user "Ref Des/Silkscreen Top")
		(7 "B.SilkS" user "Ref Des/Silkscreen Bottom")
		(1 "F.Mask" user "Board Geometry/Soldermask Top")
		(3 "B.Mask" user "Board Geometry/Soldermask Bottom")
		(17 "Dwgs.User" user "User.Drawings")
		(19 "Cmts.User" user "User.Comments")
		(21 "Eco1.User" user "User.Eco1")
		(23 "Eco2.User" user "User.Eco2")
		(25 "Edge.Cuts" user "Board Geometry/Outline")
		(27 "Margin" user)
		(31 "F.CrtYd" user "Package Geometry/Place Bound Top")
		(29 "B.CrtYd" user "Package Geometry/Place Bound Bottom")
		(35 "F.Fab" user "Ref Des/Assembly Top")
		(33 "B.Fab" user "Ref Des/Assembly Bottom")
	)
	(footprint ""
		(layer "B.Cu")
		(at 259.097526 -76.558902 -90)
		(property "Reference" "PR1649"
			(at 0 0 90)
			(layer "B.SilkS")
			(hide yes)
			(effects
				(font
					(size 1.27 1.27)
				)
				(justify mirror)
			)
		)
		(property "Value" ""
			(at 0 0 90)
			(layer "B.Fab")
			(effects
				(font
					(size 1.27 1.27)
				)
				(justify mirror)
			)
		)
		(duplicate_pad_numbers_are_jumpers no)
		(fp_line
			(start -0.7874 0.4064)
			(end 0.7874 0.4064)
			(stroke
				(width 0.1524)
				(type default)
			)
			(layer "B.SilkS")
		)
		(fp_line
			(start 0.7874 0.4064)
			(end 0.7874 -0.4064)
			(stroke
				(width 0.1524)
				(type default)
			)
			(layer "B.SilkS")
		)
		(fp_line
			(start -0.7874 -0.4064)
			(end -0.7874 0.4064)
			(stroke
				(width 0.1524)
				(type default)
			)
			(layer "B.SilkS")
		)
		(fp_line
			(start 0.7874 -0.4064)
			(end -0.7874 -0.4064)
			(stroke
				(width 0.1524)
				(type default)
			)
			(layer "B.SilkS")
		)
		(fp_line
			(start -0.67945 0.3048)
			(end -0.120396 0.3048)
			(stroke
				(width 0.1)
				(type default)
			)
			(layer "B.Fab")
		)
		(fp_line
			(start -0.120396 0.3048)
			(end -0.120396 0.2794)
			(stroke
				(width 0.1)
				(type default)
			)
			(layer "B.Fab")
		)
		(fp_line
			(start 0.12065 0.3048)
			(end 0.67945 0.3048)
			(stroke
				(width 0.1)
				(type default)
			)
			(layer "B.Fab")
		)
		(fp_line
			(start 0.67945 0.3048)
			(end 0.67945 -0.305054)
			(stroke
				(width 0.1)
				(type default)
			)
			(layer "B.Fab")
		)
		(fp_line
			(start -0.120396 0.2794)
			(end 0.12065 0.2794)
			(stroke
				(width 0.1)
				(type default)
			)
			(layer "B.Fab")
		)
		(fp_line
			(start 0.12065 0.2794)
			(end 0.12065 0.3048)
			(stroke
				(width 0.1)
				(type default)
			)
			(layer "B.Fab")
		)
		(fp_line
			(start -0.12065 -0.2794)
			(end -0.12065 -0.3048)
			(stroke
				(width 0.1)
				(type default)
			)
			(layer "B.Fab")
		)
		(fp_line
			(start 0.12065 -0.2794)
			(end -0.12065 -0.2794)
			(stroke
				(width 0.1)
				(type default)
			)
			(layer "B.Fab")
		)
		(fp_line
			(start -0.67945 -0.3048)
			(end -0.67945 0.3048)
			(stroke
				(width 0.1)
				(type default)
			)
			(layer "B.Fab")
		)
		(fp_line
			(start -0.12065 -0.3048)
			(end -0.67945 -0.3048)
			(stroke
				(width 0.1)
				(type default)
			)
			(layer "B.Fab")
		)
		(fp_line
			(start 0.12065 -0.305054)
			(end 0.12065 -0.2794)
			(stroke
				(width 0.1)
				(type default)
			)
			(layer "B.Fab")
		)
		(fp_line
			(start 0.67945 -0.305054)
			(end 0.12065 -0.305054)
			(stroke
				(width 0.1)
				(type default)
			)
			(layer "B.Fab")
		)
		(pad "1" smd circle
			(at 0.40005 0 90)
			(size 0 0)
			(layers "B.Cu" "B.Mask" "B.Paste")
			(net "FM_P1V05_PCH_AUX_R_EN")
		)
		(pad "2" smd circle
			(at -0.40005 0 90)
			(size 0 0)
			(layers "B.Cu" "B.Mask" "B.Paste")
			(net "GND")
		)
	)
	(footprint ""
		(layer "B.Cu")
		(at 266.065 -98.008948 -90)
		(property "Reference" "C107"
			(at 0 0 90)
			(layer "B.SilkS")
			(hide yes)
			(effects
				(font
					(size 1.27 1.27)
				)
				(justify mirror)
			)
		)
		(property "Value" ""
			(at 0 0 90)
			(layer "B.Fab")
			(effects
				(font
					(size 1.27 1.27)
				)
				(justify mirror)
			)
		)
		(duplicate_pad_numbers_are_jumpers no)
		(fp_line
			(start -0.7874 0.4064)
			(end 0.7874 0.4064)
			(stroke
				(width 0.1524)
				(type default)
			)
			(layer "B.SilkS")
		)
		(fp_line
			(start 0.7874 0.4064)
			(end 0.7874 -0.4064)
			(stroke
				(width 0.1524)
				(type default)
			)
			(layer "B.SilkS")
		)
		(fp_line
			(start -0.7874 -0.4064)
			(end -0.7874 0.4064)
			(stroke
				(width 0.1524)
				(type default)
			)
			(layer "B.SilkS")
		)
		(fp_line
			(start 0.7874 -0.4064)
			(end -0.7874 -0.4064)
			(stroke
				(width 0.1524)
				(type default)
			)
			(layer "B.SilkS")
		)
		(fp_line
			(start -0.67945 0.3048)
			(end -0.120396 0.3048)
			(stroke
				(width 0.1)
				(type default)
			)
			(layer "B.Fab")
		)
		(fp_line
			(start -0.120396 0.3048)
			(end -0.120396 0.2794)
			(stroke
				(width 0.1)
				(type default)
			)
			(layer "B.Fab")
		)
		(fp_line
			(start 0.12065 0.3048)
			(end 0.67945 0.3048)
			(stroke
				(width 0.1)
				(type default)
			)
			(layer "B.Fab")
		)
		(fp_line
			(start 0.67945 0.3048)
			(end 0.67945 -0.305054)
			(stroke
				(width 0.1)
				(type default)
			)
			(layer "B.Fab")
		)
		(fp_line
			(start -0.120396 0.2794)
			(end 0.12065 0.2794)
			(stroke
				(width 0.1)
				(type default)
			)
			(layer "B.Fab")
		)
		(fp_line
			(start 0.12065 0.2794)
			(end 0.12065 0.3048)
			(stroke
				(width 0.1)
				(type default)
			)
			(layer "B.Fab")
		)
		(fp_line
			(start -0.12065 -0.2794)
			(end -0.12065 -0.3048)
			(stroke
				(width 0.1)
				(type default)
			)
			(layer "B.Fab")
		)
		(fp_line
			(start 0.12065 -0.2794)
			(end -0.12065 -0.2794)
			(stroke
				(width 0.1)
				(type default)
			)
			(layer "B.Fab")
		)
		(fp_line
			(start -0.67945 -0.3048)
			(end -0.67945 0.3048)
			(stroke
				(width 0.1)
				(type default)
			)
			(layer "B.Fab")
		)
		(fp_line
			(start -0.12065 -0.3048)
			(end -0.67945 -0.3048)
			(stroke
				(width 0.1)
				(type default)
			)
			(layer "B.Fab")
		)
		(fp_line
			(start 0.12065 -0.305054)
			(end 0.12065 -0.2794)
			(stroke
				(width 0.1)
				(type default)
			)
			(layer "B.Fab")
		)
		(fp_line
			(start 0.67945 -0.305054)
			(end 0.12065 -0.305054)
			(stroke
				(width 0.1)
				(type default)
			)
			(layer "B.Fab")
		)
		(pad "1" smd circle
			(at 0.40005 0 90)
			(size 0 0)
			(layers "B.Cu" "B.Mask" "B.Paste")
			(net "P3V3_AUX_CLK_GEN_VDD_CK440")
		)
		(pad "2" smd circle
			(at -0.40005 0 90)
			(size 0 0)
			(layers "B.Cu" "B.Mask" "B.Paste")
			(net "GND")
		)
	)
)
